FILE_TYPE = CONNECTIVITY;
{Allegro Design Entry HDL 16.6-p007 (v16-6-112F) 10/10/2012}
"PAGE_NUMBER" = 192;
0"NC";
1"GND\g";
2"GND\g";
3"P3V3_STBY\g";
4"P3V3_STBY\g";
5"P3V3_STBY\g";
6"P3V3_STBY\g";
7"P3V3_STBY\g";
8"P3V3_STBY\g";
9"P3V3_STBY\g";
10"GND\g";
11"PVPP_ABC\g";
12"P3V3_STBY\g";
13"P3V3_STBY\g";
14"GND\g";
15"PVPP_KLM\g";
16"FM_MEM_EVENT_FUNC";
17"PU_THERMTRIP_FORCE_N";
18"FM_PLD_DEBUG_MODE_N";
19"RST_RSMRST_N";
20"RST_CD_CPU1_POR_N";
21"RST_CD_CPU0_POR_N";
22"PU_RST_PERST_BIT1";
23"PU_RST_PERST_BIT0";
%"CAP_A"
"1","(-1225,1975)","0","dev_discrete","I1";
;
LOCATION"C2P8"
PART_NUMBER"A36096-045"
VALUE"0.01UF"
TOLERANCE"10%"
PACK_TYPE"0402V"
VOLTAGE"25V"
MATERIAL"X7R"
ROOM"CPLD"
CDS_LOCATION"C2P8"
BOM_COST"CPLD"
SIGNAL_MODEL"DEFAULT_CAPACITOR_10000pF_2_1"
CDS_SEC"1"
$SEC"1"
CDS_LIB"dev_discrete";
"B"
$PN"2"1;
"A"
$PN"1"4;
%"CAP_A"
"1","(-4075,1975)","0","dev_discrete","I10";
;
LOCATION"C3R2"
PART_NUMBER"A36096-030"
VALUE"0.1UF"
TOLERANCE"10%"
PACK_TYPE"0402V"
VOLTAGE"16V"
MATERIAL"X7R"
ROOM"CPLD"
SIGNAL_MODEL"DEFAULT_CAPACITOR_100000pF_2_1"
BOM_COST"CPLD"
CDS_SEC"1"
$SEC"1"
CDS_LOCATION"C3R2"
CDS_LIB"dev_discrete";
"B"
$PN"2"1;
"A"
$PN"1"4;
%"CAP_A"
"1","(-3700,1300)","0","dev_discrete","I11";
;
LOCATION"C3P51"
PART_NUMBER"A36096-030"
VALUE"0.1UF"
TOLERANCE"10%"
PACK_TYPE"0402V"
VOLTAGE"16V"
MATERIAL"X7R"
ROOM"CPLD"
$SEC"1"
CDS_SEC"1"
BOM_COST"CPLD"
SIGNAL_MODEL"DEFAULT_CAPACITOR_100000pF_2_1"
CDS_LOCATION"C3P51"
CDS_LIB"dev_discrete";
"B"
$PN"2"2;
"A"
$PN"1"5;
%"CAP_A"
"1","(-4200,1300)","0","dev_discrete","I12";
;
LOCATION"C3P47"
PART_NUMBER"A36096-030"
VALUE"0.1UF"
TOLERANCE"10%"
VOLTAGE"16V"
MATERIAL"X7R"
PACK_TYPE"0402V"
ROOM"CPLD"
$SEC"1"
CDS_SEC"1"
BOM_COST"CPLD"
SIGNAL_MODEL"DEFAULT_CAPACITOR_100000pF_2_1"
CDS_LOCATION"C3P47"
CDS_LIB"dev_discrete";
"B"
$PN"2"2;
"A"
$PN"1"5;
%"LCMXO2_A"
"6","(-1850,3900)","0","mstr_memory","I14";
;
CDS_SEC"3"
LOCATION"U8D7"
MATERIAL"IC"
PART_NUMBER"H63395-001"
PACK_TYPE"256BGA"
ROOM"CPLD"
SEC_TYPE"256BGA"
SEC"3"
CDS_LIB"mstr_memory"
CDS_LMAN_SYM_OUTLINE"-400,750,400,-750"
BOM_COST"CPLD"
CDS_LOCATION"U8D7";
"VCC<3>"
$PN"T16"3;
"VCC<2>"
$PN"T1"3;
"VCC<1>"
$PN"A16"3;
"VCC<0>"
$PN"A1"3;
"GND<14>"
$PN"L6"10;
"GND<23>"
$PN"R15"10;
"NC<0>"
$PN"A2"0;
"GND<0>"
$PN"B2"10;
"GND<1>"
$PN"B15"10;
"GND<2>"
$PN"C3"10;
"GND<3>"
$PN"C14"10;
"GND<4>"
$PN"D4"10;
"GND<5>"
$PN"D13"10;
"GND<6>"
$PN"E5"10;
"GND<7>"
$PN"E12"10;
"GND<8>"
$PN"F6"10;
"GND<9>"
$PN"F11"10;
"GND<10>"
$PN"H8"10;
"GND<11>"
$PN"H9"10;
"GND<12>"
$PN"J8"10;
"GND<13>"
$PN"J9"10;
"GND<15>"
$PN"L11"10;
"GND<16>"
$PN"M5"10;
"GND<17>"
$PN"M12"10;
"GND<18>"
$PN"N4"10;
"GND<19>"
$PN"N13"10;
"GND<20>"
$PN"P3"10;
"GND<21>"
$PN"P14"10;
"GND<22>"
$PN"R2"10;
"VCC<4>"
$PN"G7"3;
"VCC<5>"
$PN"G10"3;
"VCC<6>"
$PN"K7"3;
"VCC<7>"
$PN"K10"3;
"VCCIO0<0>"
$PN"G8"3;
"VCCIO0<1>"
$PN"D12"3;
"VCCIO0<2>"
$PN"G9"3;
"VCCIO1<0>"
$PN"E13"3;
"VCCIO1<1>"
$PN"H10"3;
"VCCIO1<2>"
$PN"J10"3;
"VCCIO1<3>"
$PN"M13"3;
"VCCIO2<0>"
$PN"K9"3;
"VCCIO2<1>"
$PN"N12"3;
"VCCIO2<2>"
$PN"K8"3;
"VCCIO2<3>"
$PN"N5"3;
"VCCIO4<0>"
$PN"J7"3;
"VCCIO4<1>"
$PN"H7"3;
"VCCIO5<0>"
$PN"E4"3;
"VCCIO0<3>"
$PN"D5"3;
"VCCIO3<0>"
$PN"M4"3;
%"CAP_A"
"1","(-4550,1975)","0","dev_discrete","I15";
;
LOCATION"C2R5"
PART_NUMBER"A36096-030"
VALUE"0.1UF"
TOLERANCE"10%"
PACK_TYPE"0402V"
VOLTAGE"16V"
MATERIAL"X7R"
ROOM"CPLD"
SIGNAL_MODEL"DEFAULT_CAPACITOR_100000pF_2_1"
BOM_COST"CPLD"
CDS_SEC"1"
$SEC"1"
CDS_LOCATION"C2R5"
CDS_LIB"dev_discrete";
"B"
$PN"2"1;
"A"
$PN"1"4;
%"CAP_A"
"1","(-5025,1975)","0","dev_discrete","I16";
;
LOCATION"C2P4"
PART_NUMBER"A36096-030"
VALUE"0.1UF"
TOLERANCE"10%"
PACK_TYPE"0402V"
VOLTAGE"16V"
MATERIAL"X7R"
ROOM"CPLD"
CDS_LOCATION"C2P4"
SIGNAL_MODEL"DEFAULT_CAPACITOR_100000pF_2_1"
BOM_COST"CPLD"
CDS_SEC"1"
$SEC"1"
CDS_LIB"dev_discrete";
"B"
$PN"2"1;
"A"
$PN"1"4;
%"CAP_A"
"1","(-4725,1300)","0","dev_discrete","I17";
;
LOCATION"C3P52"
PART_NUMBER"A36096-030"
VALUE"0.1UF"
TOLERANCE"10%"
PACK_TYPE"0402V"
VOLTAGE"16V"
MATERIAL"X7R"
ROOM"CPLD"
CDS_SEC"1"
$SEC"1"
BOM_COST"CPLD"
SIGNAL_MODEL"DEFAULT_CAPACITOR_100000pF_2_1"
CDS_LOCATION"C3P52"
CDS_LIB"dev_discrete";
"B"
$PN"2"2;
"A"
$PN"1"5;
%"CAP_A"
"1","(-5225,1300)","0","dev_discrete","I18";
;
LOCATION"C2P6"
PART_NUMBER"A36096-030"
VALUE"0.1UF"
TOLERANCE"10%"
PACK_TYPE"0402V"
VOLTAGE"16V"
MATERIAL"X7R"
ROOM"CPLD"
$SEC"1"
CDS_SEC"1"
BOM_COST"CPLD"
SIGNAL_MODEL"DEFAULT_CAPACITOR_100000pF_2_1"
CDS_LOCATION"C2P6"
CDS_LIB"dev_discrete";
"B"
$PN"2"2;
"A"
$PN"1"5;
%"CAP_A"
"1","(-5500,1975)","0","dev_discrete","I19";
;
LOCATION"C2R3"
PART_NUMBER"A36096-030"
VALUE"0.1UF"
TOLERANCE"10%"
PACK_TYPE"0402V"
VOLTAGE"16V"
MATERIAL"X7R"
ROOM"CPLD"
$SEC"1"
CDS_SEC"1"
BOM_COST"CPLD"
SIGNAL_MODEL"DEFAULT_CAPACITOR_100000pF_2_1"
CDS_LOCATION"C2R3"
CDS_LIB"dev_discrete";
"B"
$PN"2"1;
"A"
$PN"1"4;
%"GND"
"1","(-1225,1625)","0","mstr_symbols","I2";
;
VOLTAGE"0.0V"
ROOM"CPLD"
SIZE"1B"
CDS_LIB"mstr_symbols"
BOM_COST"CPLD"
BODY_TYPE"PLUMBING"
HDL_POWER"GND";
"A\NAC"1;
%"CAP_A"
"1","(-5975,1975)","0","dev_discrete","I20";
;
LOCATION"C2P7"
PART_NUMBER"A36096-030"
VALUE"0.1UF"
TOLERANCE"10%"
PACK_TYPE"0402V"
VOLTAGE"16V"
MATERIAL"X7R"
ROOM"CPLD"
$SEC"1"
CDS_SEC"1"
SIGNAL_MODEL"DEFAULT_CAPACITOR_100000pF_2_1"
BOM_COST"CPLD"
CDS_LOCATION"C2P7"
CDS_LIB"dev_discrete";
"B"
$PN"2"1;
"A"
$PN"1"4;
%"CAP_A"
"1","(-5700,1300)","0","dev_discrete","I21";
;
LOCATION"C2R4"
PART_NUMBER"A36096-030"
VALUE"0.1UF"
TOLERANCE"10%"
PACK_TYPE"0402V"
VOLTAGE"16V"
MATERIAL"X7R"
ROOM"CPLD"
CDS_SEC"1"
$SEC"1"
BOM_COST"CPLD"
SIGNAL_MODEL"DEFAULT_CAPACITOR_100000pF_2_1"
CDS_LOCATION"C2R4"
CDS_LIB"dev_discrete";
"B"
$PN"2"2;
"A"
$PN"1"5;
%"CAP_A"
"1","(-6250,1300)","0","dev_discrete","I22";
;
LOCATION"C2P3"
PART_NUMBER"A36096-030"
VALUE"0.1UF"
TOLERANCE"10%"
PACK_TYPE"0402V"
VOLTAGE"16V"
MATERIAL"X7R"
ROOM"CPLD"
$SEC"1"
CDS_SEC"1"
BOM_COST"CPLD"
SIGNAL_MODEL"DEFAULT_CAPACITOR_100000pF_2_1"
CDS_LOCATION"C2P3"
CDS_LIB"dev_discrete";
"B"
$PN"2"2;
"A"
$PN"1"5;
%"CAP_A"
"1","(-6450,1975)","0","dev_discrete","I23";
;
LOCATION"C3P44"
PART_NUMBER"A36096-030"
VALUE"0.1UF"
TOLERANCE"10%"
PACK_TYPE"0402V"
VOLTAGE"16V"
MATERIAL"X7R"
ROOM"CPLD"
CDS_LOCATION"C3P44"
BOM_COST"CPLD"
SIGNAL_MODEL"DEFAULT_CAPACITOR_100000pF_2_1"
CDS_SEC"1"
$SEC"1"
CDS_LIB"dev_discrete";
"B"
$PN"2"1;
"A"
$PN"1"4;
%"CAP_A"
"1","(-6925,1975)","0","dev_discrete","I25";
;
LOCATION"C3P48"
PART_NUMBER"A36096-030"
VALUE"0.1UF"
TOLERANCE"10%"
PACK_TYPE"0402V"
VOLTAGE"16V"
MATERIAL"X7R"
ROOM"CPLD"
SEC"1"
SEC_TYPE"0402V"
CDS_SEC"1"
BOM_COST"CPLD"
SIGNAL_MODEL"DEFAULT_CAPACITOR_100000pF_2_1"
CDS_LOCATION"C3P48"
CDS_LIB"dev_discrete";
"B"
$PN"2"1;
"A"
$PN"1"4;
%"GND"
"1","(-6475,1000)","0","mstr_symbols","I26";
;
VOLTAGE"0.0V"
ROOM"CPLD"
BOM_COST"CPLD"
CDS_LIB"mstr_symbols"
SIZE"1B"
BODY_TYPE"PLUMBING"
HDL_POWER"GND";
"A\NAC"2;
%"CAP_A"
"1","(-6850,1300)","0","dev_discrete","I28";
;
LOCATION"C2R2"
PART_NUMBER"A36096-030"
VALUE"0.1UF"
TOLERANCE"10%"
PACK_TYPE"0402V"
VOLTAGE"16V"
MATERIAL"X7R"
ROOM"CPLD"
$SEC"1"
CDS_SEC"1"
BOM_COST"CPLD"
SIGNAL_MODEL"DEFAULT_CAPACITOR_100000pF_2_1"
CDS_LOCATION"C2R2"
CDS_LIB"dev_discrete";
"B"
$PN"2"2;
"A"
$PN"1"5;
%"P3V3_STBY"
"1","(-2500,4700)","0","mstr_symbols","I29";
;
VOLTAGE"3.3V"
SIZE"1B"
CDS_LIB"mstr_symbols"
BODY_TYPE"PLUMBING"
HDL_POWER"P3V3_STBY";
"G\NAC"3;
%"CAP_A"
"1","(-1700,1975)","0","dev_discrete","I3";
;
LOCATION"C2P5"
PART_NUMBER"A36096-030"
VALUE"0.1UF"
TOLERANCE"10%"
PACK_TYPE"0402V"
VOLTAGE"16V"
MATERIAL"X7R"
ROOM"CPLD"
CDS_LOCATION"C2P5"
SIGNAL_MODEL"DEFAULT_CAPACITOR_100000pF_2_1"
BOM_COST"CPLD"
CDS_SEC"1"
$SEC"1"
CDS_LIB"dev_discrete";
"B"
$PN"2"1;
"A"
$PN"1"4;
%"P3V3_STBY"
"1","(-6925,2275)","0","mstr_symbols","I30";
;
VOLTAGE"3.3V"
SIZE"1B"
CDS_LIB"mstr_symbols"
BODY_TYPE"PLUMBING"
HDL_POWER"P3V3_STBY";
"G\NAC"4;
%"P3V3_STBY"
"1","(-6850,1525)","0","mstr_symbols","I31";
;
VOLTAGE"3.3V"
SIZE"1B"
CDS_LIB"mstr_symbols"
BODY_TYPE"PLUMBING"
HDL_POWER"P3V3_STBY";
"G\NAC"5;
%"P3V3_STBY"
"1","(-6150,4600)","0","mstr_symbols","I32";
;
VOLTAGE"3.3V"
SIZE"1B"
CDS_LIB"mstr_symbols"
BODY_TYPE"PLUMBING"
HDL_POWER"P3V3_STBY";
"G\NAC"6;
%"RES"
"2","(-6150,4400)","0","mstr_discrete","I33";
;
CDS_SEC"1"
LOCATION"R7E6"
VALUE"10.0K"
TOLERANCE"1%"
PART_NUMBER"G21796-016"
MATERIAL"CHIP"
WATTAGE"1/16W"
PACK_TYPE"0402"
ROOM"CPLD"
BOM_COST"CPLD"
CDS_LOCATION"R7E6"
CDS_LIB"mstr_discrete"
SEC"1"
SEC_TYPE"0402";
"A"
$PN"1"6;
"B"
$PN"2"22;
%"RES"
"2","(-5750,4400)","0","mstr_discrete","I34";
;
CDS_SEC"1"
VALUE"10.0K"
TOLERANCE"1%"
MATERIAL"CHIP"
PACK_TYPE"0402"
WATTAGE"1/16W"
LOCATION"R2R1"
PART_NUMBER"G21796-016"
ROOM"CPLD"
BOM_COST"CPLD"
CDS_LOCATION"R2R1"
CDS_LIB"mstr_discrete"
SEC"1"
SEC_TYPE"0402";
"A"
$PN"1"7;
"B"
$PN"2"23;
%"P3V3_STBY"
"1","(-5750,4600)","0","mstr_symbols","I35";
;
VOLTAGE"3.3V"
SIZE"1B"
CDS_LIB"mstr_symbols"
BODY_TYPE"PLUMBING"
HDL_POWER"P3V3_STBY";
"G\NAC"7;
%"RES"
"2","(-6550,4400)","0","mstr_discrete","I38";
;
LOCATION"R7E5"
PACK_TYPE"0402"
PART_NUMBER"G21796-016"
MATERIAL"CHIP"
WATTAGE"1/16W"
TOLERANCE"1%"
VALUE"10.0K"
ROOM"CPLD"
$SEC"1"
CDS_SEC"1"
BOM_COST"CPLD"
CDS_LOCATION"R7E5"
CDS_LIB"mstr_discrete";
"A"
$PN"1"8;
"B"
$PN"2"17;
%"P3V3_STBY"
"1","(-6550,4600)","0","mstr_symbols","I39";
;
VOLTAGE"3.3V"
SIZE"1B"
CDS_LIB"mstr_symbols"
BODY_TYPE"PLUMBING"
HDL_POWER"P3V3_STBY";
"G\NAC"8;
%"CAP_A"
"1","(-2175,1975)","0","dev_discrete","I4";
;
LOCATION"C3R1"
PART_NUMBER"A36096-030"
VALUE"0.1UF"
TOLERANCE"10%"
PACK_TYPE"0402V"
VOLTAGE"16V"
MATERIAL"X7R"
ROOM"CPLD"
CDS_SEC"1"
BOM_COST"CPLD"
$SEC"1"
SIGNAL_MODEL"DEFAULT_CAPACITOR_100000pF_2_1"
CDS_LOCATION"C3R1"
CDS_LIB"dev_discrete";
"B"
$PN"2"1;
"A"
$PN"1"4;
%"RES"
"2","(-6950,4400)","0","mstr_discrete","I41";
;
VALUE"10.0K"
TOLERANCE"1%"
LOCATION"R2R3"
MATERIAL"CHIP"
WATTAGE"1/16W"
PACK_TYPE"0402"
PART_NUMBER"G21796-016"
ROOM"CPLD"
$SEC"1"
CDS_SEC"1"
BOM_COST"CPLD"
CDS_LOCATION"R2R3"
CDS_LIB"mstr_discrete";
"A"
$PN"1"9;
"B"
$PN"2"18;
%"P3V3_STBY"
"1","(-6950,4600)","0","mstr_symbols","I42";
;
VOLTAGE"3.3V"
SIZE"1B"
CDS_LIB"mstr_symbols"
BODY_TYPE"PLUMBING"
HDL_POWER"P3V3_STBY";
"G\NAC"9;
%"RES"
"2","(-6150,2800)","0","mstr_discrete","I48";
;
CDS_SEC"1"
CDS_LOCATION"R3R16"
LOCATION"R3R16"
PART_NUMBER"G21796-072"
VALUE"4.75K"
TOLERANCE"1%"
PACK_TYPE"0402"
WATTAGE"1/16W"
MATERIAL"CHIP"
ROOM"CPLD"
BOM_COST"CPLD"
SEC"1"
SEC_TYPE"0402"
CDS_LIB"mstr_discrete";
"A"
$PN"1"11;
"B"
$PN"2"21;
%"RES"
"2","(-5750,2800)","0","mstr_discrete","I49";
;
CDS_SEC"1"
CDS_LOCATION"R6M9"
LOCATION"R6M9"
PART_NUMBER"G21796-072"
VALUE"4.75K"
TOLERANCE"1%"
PACK_TYPE"0402"
MATERIAL"CHIP"
WATTAGE"1/16W"
ROOM"CPLD"
SEC"1"
SEC_TYPE"0402"
BOM_COST"CPLD"
CDS_LIB"mstr_discrete";
"A"
$PN"1"15;
"B"
$PN"2"20;
%"GND"
"1","(-1100,3100)","0","mstr_symbols","I5";
;
VOLTAGE"0.0V"
ROOM"CPLD"
CDS_LIB"mstr_symbols"
BOM_COST"CPLD"
SIZE"1B"
BODY_TYPE"PLUMBING"
HDL_POWER"GND";
"A\NAC"10;
%"PVPP_ABC"
"1","(-6150,3000)","0","mstr_symbols","I52";
;
VOLTAGE"2.5V"
ROOM"PVPP_KLM_VR"
BOM_COST"PVPP_KLM_VR"
CDS_LIB"mstr_symbols"
BODY_TYPE"PLUMBING"
HDL_POWER"PVPP_ABC";
"G\NAC"11;
%"RES"
"2","(-7350,4400)","0","mstr_discrete","I55";
;
CDS_SEC"1"
CDS_LOCATION"R7E18"
LOCATION"R7E18"
VALUE"4.75K"
PART_NUMBER"G21796-072"
WATTAGE"1/16W"
TOLERANCE"1%"
POP"NOPOP"
MATERIAL"CHIP"
PACK_TYPE"0402"
ROOM"CPLD"
BOM_COST"CPLD"
CDS_LIB"mstr_discrete"
SEC"1"
SEC_TYPE"0402";
"A"
$PN"1"12;
"B"
$PN"2"19;
%"P3V3_STBY"
"1","(-7350,4600)","0","mstr_symbols","I56";
;
VOLTAGE"3.3V"
SIZE"1B"
CDS_LIB"mstr_symbols"
BODY_TYPE"PLUMBING"
HDL_POWER"P3V3_STBY";
"G\NAC"12;
%"RES"
"2","(-7750,4400)","0","mstr_discrete","I57";
;
CDS_SEC"1"
CDS_LOCATION"R7E19"
WATTAGE"1/16W"
TOLERANCE"1%"
VALUE"1.00K"
LOCATION"R7E19"
PART_NUMBER"G21796-026"
PACK_TYPE"0402"
MATERIAL"EMPTY"
ROOM"CPLD"
BOM_COST"CPLD"
CDS_LIB"mstr_discrete"
SEC"1"
SEC_TYPE"0402";
"A"
$PN"1"13;
"B"
$PN"2"16;
%"P3V3_STBY"
"1","(-7750,4600)","0","mstr_symbols","I58";
;
VOLTAGE"3.3V"
SIZE"1B"
CDS_LIB"mstr_symbols"
BODY_TYPE"PLUMBING"
HDL_POWER"P3V3_STBY";
"G\NAC"13;
%"RES"
"2","(-7750,3500)","0","mstr_discrete","I59";
;
CDS_SEC"1"
CDS_LOCATION"R7E20"
LOCATION"R7E20"
VALUE"1.00K"
TOLERANCE"1%"
PART_NUMBER"G21796-026"
MATERIAL"CHIP"
WATTAGE"1/16W"
PACK_TYPE"0402"
ROOM"CPLD"
BOM_COST"CPLD"
CDS_LIB"mstr_discrete"
SEC"1"
SEC_TYPE"0402";
"A"
$PN"1"16;
"B"
$PN"2"14;
%"CAP_A"
"1","(-2650,1975)","0","dev_discrete","I6";
;
LOCATION"C3P43"
PART_NUMBER"A36096-030"
VALUE"0.1UF"
TOLERANCE"10%"
PACK_TYPE"0402V"
VOLTAGE"16V"
MATERIAL"X7R"
ROOM"CPLD"
$SEC"1"
CDS_SEC"1"
BOM_COST"CPLD"
SIGNAL_MODEL"DEFAULT_CAPACITOR_100000pF_2_1"
CDS_LOCATION"C3P43"
CDS_LIB"dev_discrete";
"B"
$PN"2"1;
"A"
$PN"1"4;
%"GND"
"1","(-7750,3300)","0","mstr_symbols","I61";
;
VOLTAGE"0.0V"
SIZE"1B"
CDS_LIB"mstr_symbols"
BODY_TYPE"PLUMBING"
HDL_POWER"GND";
"A\NAC"14;
%"PVPP_KLM"
"1","(-5750,3000)","0","mstr_symbols","I62";
;
VOLTAGE"2.5V"
ROOM"PVPP_KLM_VR"
BOM_COST"PVPP_KLM_VR"
CDS_LIB"mstr_symbols"
BODY_TYPE"PLUMBING"
HDL_POWER"PVPP_KLM";
"G\NAC"15;
%"CAP_A"
"1","(-3125,1975)","0","dev_discrete","I7";
;
LOCATION"C3R3"
PART_NUMBER"A36096-030"
VALUE"0.1UF"
TOLERANCE"10%"
PACK_TYPE"0402V"
VOLTAGE"16V"
MATERIAL"X7R"
ROOM"CPLD"
SIGNAL_MODEL"DEFAULT_CAPACITOR_100000pF_2_1"
BOM_COST"CPLD"
CDS_SEC"1"
$SEC"1"
CDS_LOCATION"C3R3"
CDS_LIB"dev_discrete";
"B"
$PN"2"1;
"A"
$PN"1"4;
%"CAP_A"
"1","(-3150,1300)","0","dev_discrete","I8";
;
LOCATION"C2R1"
PART_NUMBER"A36096-030"
VALUE"0.1UF"
TOLERANCE"10%"
PACK_TYPE"0402V"
VOLTAGE"16V"
MATERIAL"X7R"
ROOM"CPLD"
$SEC"1"
CDS_SEC"1"
BOM_COST"CPLD"
SIGNAL_MODEL"DEFAULT_CAPACITOR_100000pF_2_1"
CDS_LIB"dev_discrete"
CDS_LOCATION"C2R1";
"B"
$PN"2"2;
"A"
$PN"1"5;
%"CAP_A"
"1","(-3600,1975)","0","dev_discrete","I9";
;
LOCATION"C2P2"
PART_NUMBER"A36096-030"
VALUE"0.1UF"
TOLERANCE"10%"
PACK_TYPE"0402V"
VOLTAGE"16V"
MATERIAL"X7R"
ROOM"CPLD"
$SEC"1"
CDS_SEC"1"
BOM_COST"CPLD"
SIGNAL_MODEL"DEFAULT_CAPACITOR_100000pF_2_1"
CDS_LOCATION"C2P2"
CDS_LIB"dev_discrete";
"B"
$PN"2"1;
"A"
$PN"1"4;
END.
